(kicad_pcb
	(version 20221018)
	(generator pcbnew)
	(general
    (thickness 1.6)
  )
	(paper "A4")
	(title_block
    (title "NUC Computer Cluster Power Breakout HW")
    (date "2023-10-18")
    (rev "1.4.3")
    (company "Antmicro Ltd.")
		(comment 9 "footprints 192-198 of 234")
	)
	(layers
    (0 "F.Cu" mixed)
    (1 "In1.Cu" power)
    (2 "In2.Cu" mixed)
    (31 "B.Cu" power)
    (32 "B.Adhes" user "B.Adhesive")
    (33 "F.Adhes" user "F.Adhesive")
    (34 "B.Paste" user)
    (35 "F.Paste" user)
    (36 "B.SilkS" user "B.Silkscreen")
    (37 "F.SilkS" user "F.Silkscreen")
    (38 "B.Mask" user)
    (39 "F.Mask" user)
    (40 "Dwgs.User" user "User.Drawings")
    (41 "Cmts.User" user "User.Comments")
    (42 "Eco1.User" user "User.Eco1")
    (43 "Eco2.User" user "User.Eco2")
    (44 "Edge.Cuts" user)
    (45 "Margin" user)
    (46 "B.CrtYd" user "B.Courtyard")
    (47 "F.CrtYd" user "F.Courtyard")
    (48 "B.Fab" user)
    (49 "F.Fab" user)
  )
	(footprint "antmicro-footprints:FB_0603_1608Metric" (layer "F.Cu")
    (at 149.625 105.05)
    (property "Author" "Antmicro")
    (property "Current" "")
    (property "License" "Apache-2.0")
    (property "MPN" "BLM18AG601SN1D")
    (property "Manufacturer" "Murata")
    (property "Sheetfile" "pow-cycl-curr-meas.kicad_sch")
    (property "Sheetname" "Power Cycling & Current Measurement")
    (property "Val" "600Z/0.5A")
    (property "ki_description" "Ferrite Bead, 0603 [1608 Metric], 600 ohm, 500 mA, BLM18A, 0.38 ohm, ± 25%, General use")
    (property "ki_keywords" "0603, SMT, FERRITE BEAD, PASSIVE")
    (attr smd)
    (fp_text reference "FB4" (at -1.025 1.65) (layer "F.SilkS")
        (effects (font (size 0.7 0.7) (thickness 0.15)) (justify left bottom))
    )
    (fp_text value "FB_600Z_0.5A_Murata-BLM18AG_0603" (at 0 1.5) (layer "F.Fab")
        (effects (font (size 0.7 0.7) (thickness 0.15)) (justify left bottom))
    )
    (fp_text user "License: Apache-2.0" (at -1.653 5.9) (layer "F.Fab") hide
        (effects (font (size 0.7 0.7) (thickness 0.15)) (justify left bottom))
    )
    (fp_text user "Author: Antmicro" (at -1.653 3.162) (layer "F.Fab") hide
        (effects (font (size 0.7 0.7) (thickness 0.15)) (justify left bottom))
    )
    (fp_text user "${REFERENCE}" (at -1.653 4.6) (layer "F.Fab") hide
        (effects (font (size 0.7 0.7) (thickness 0.15)) (justify left bottom))
    )
    (fp_line (start -0.15 -0.4) (end 0.15 -0.4)
      (stroke (width 0.15) (type solid)) (layer "F.SilkS"))
    (fp_line (start -0.15 0.4) (end 0.15 0.4)
      (stroke (width 0.15) (type solid)) (layer "F.SilkS"))
    (fp_rect (start -1.25 -0.65) (end 1.25 0.65)
      (stroke (width 0.05) (type solid)) (fill none) (layer "F.CrtYd"))
    (fp_line (start -0.803 0.406) (end -0.803 -0.408)
      (stroke (width 0.15) (type solid)) (layer "F.Fab"))
    (fp_line (start 0.8 -0.408) (end -0.803 -0.408)
      (stroke (width 0.15) (type solid)) (layer "F.Fab"))
    (fp_line (start 0.8 -0.408) (end 0.8 0.406)
      (stroke (width 0.15) (type solid)) (layer "F.Fab"))
    (fp_line (start 0.8 0.406) (end -0.803 0.406)
      (stroke (width 0.15) (type solid)) (layer "F.Fab"))
    (pad "1" smd roundrect (at -0.7 0) (size 0.8 1) (layers "F.Cu" "F.Paste" "F.Mask") (roundrect_rratio 0.2)
      (net 1 "VCC3V3") (pintype "passive"))
    (pad "2" smd roundrect (at 0.7 0) (size 0.8 1) (layers "F.Cu" "F.Paste" "F.Mask") (roundrect_rratio 0.2)
      (net 34 "Net-(U14-REF)") (pintype "passive"))
  )
	(footprint "antmicro-footprints:LED_0603_1608Metric_G" (layer "F.Cu")
    (at 94.2 104.4)
    (descr "LED SMD 0603 Green")
    (tags "LED SMD 0603 Green")
    (property "Author" "Antmicro")
    (property "Color" "Green")
    (property "License" "Apache-2.0")
    (property "MPN" "LG L29K-G2J1-24-Z")
    (property "Manufacturer" "OSRAM")
    (property "Sheetfile" "d1600e-psu-breakout-board.kicad_sch")
    (property "Sheetname" "")
    (property "ki_description" "LED, Green, SMD, 0603, 20 mA, 1.7 V, 570 nm")
    (property "ki_keywords" "SMT, DIODE, SEMICONDUCTOR, LED")
    (zone_connect 1)
    (attr smd)
    (fp_text reference "D11" (at -1.1 -0.6) (layer "F.SilkS")
        (effects (font (size 0.7 0.7) (thickness 0.15)) (justify left bottom))
    )
    (fp_text value "LED_G_0603_LG_L29K-G2J1-24-Z" (at -0.001 1.599) (layer "F.Fab")
        (effects (font (size 0.7 0.7) (thickness 0.15)) (justify left bottom))
    )
    (fp_text user "License: Apache-2.0" (at -1.4224 3.599) (layer "F.Fab") hide
        (effects (font (size 0.7 0.7) (thickness 0.15)) (justify left bottom))
    )
    (fp_text user "Author: Antmicro" (at -1.4224 4.799) (layer "F.Fab") hide
        (effects (font (size 0.7 0.7) (thickness 0.15)) (justify left bottom))
    )
    (fp_text user "${REFERENCE}" (at -1.4224 5.999) (layer "F.Fab") hide
        (effects (font (size 0.7 0.7) (thickness 0.15)) (justify left bottom))
    )
    (fp_line (start -1.18 -0.319) (end -1.18 0.321)
      (stroke (width 0.15) (type solid)) (layer "F.SilkS"))
    (fp_line (start -0.094672 0.001008) (end -0.24 0.001008)
      (stroke (width 0.1) (type solid)) (layer "F.SilkS"))
    (fp_line (start -0.094672 0.001008) (end 0.105328 -0.198992)
      (stroke (width 0.1) (type solid)) (layer "F.SilkS"))
    (fp_line (start -0.094672 0.201008) (end -0.094672 -0.198992)
      (stroke (width 0.1) (type solid)) (layer "F.SilkS"))
    (fp_line (start 0.105328 0.001008) (end 0.24 0.001)
      (stroke (width 0.1) (type solid)) (layer "F.SilkS"))
    (fp_line (start 0.105328 0.201008) (end -0.094672 0.001008)
      (stroke (width 0.1) (type solid)) (layer "F.SilkS"))
    (fp_line (start 0.105328 0.201008) (end 0.105328 -0.198992)
      (stroke (width 0.1) (type solid)) (layer "F.SilkS"))
    (fp_line (start 0.22 -0.35) (end -0.22 -0.35)
      (stroke (width 0.15) (type solid)) (layer "F.SilkS"))
    (fp_line (start 0.22 0.35) (end -0.22 0.35)
      (stroke (width 0.15) (type solid)) (layer "F.SilkS"))
    (fp_rect (start 1.25 0.65) (end -1.25 -0.65)
      (stroke (width 0.05) (type solid)) (fill none) (layer "F.CrtYd"))
    (fp_line (start -0.199 -0.202) (end -0.199 0.1)
      (stroke (width 0.15) (type solid)) (layer "F.Fab"))
    (fp_line (start -0.199 0) (end -0.597 0)
      (stroke (width 0.15) (type solid)) (layer "F.Fab"))
    (fp_line (start -0.199 0.2) (end -0.199 0.1)
      (stroke (width 0.15) (type solid)) (layer "F.Fab"))
    (fp_line (start -0.101 0) (end 0.201 0.2)
      (stroke (width 0.15) (type solid)) (layer "F.Fab"))
    (fp_line (start 0.201 -0.202) (end -0.101 0)
      (stroke (width 0.15) (type solid)) (layer "F.Fab"))
    (fp_line (start 0.201 0) (end 0.201 -0.202)
      (stroke (width 0.15) (type solid)) (layer "F.Fab"))
    (fp_line (start 0.201 0.2) (end 0.201 0)
      (stroke (width 0.15) (type solid)) (layer "F.Fab"))
    (fp_line (start 0.599 0) (end 0.201 0)
      (stroke (width 0.15) (type solid)) (layer "F.Fab"))
    (fp_rect (start 0.848 0.4) (end -0.85 -0.402)
      (stroke (width 0.15) (type solid)) (fill none) (layer "F.Fab"))
    (pad "1" smd roundrect (at -0.7 0 180) (size 0.8 1) (layers "F.Cu" "F.Paste" "F.Mask") (roundrect_rratio 0.2)
      (net 4 "GND") (pinfunction "C") (pintype "passive"))
    (pad "2" smd roundrect (at 0.7 0 180) (size 0.8 1) (layers "F.Cu" "F.Paste" "F.Mask") (roundrect_rratio 0.2)
      (net 82 "Net-(D11-A)") (pinfunction "A") (pintype "passive"))
  )
	(footprint "antmicro-footprints:R_0402_1005Metric" (layer "F.Cu")
    (at 142.2 97.6 180)
    (descr "Resistor SMD 0402")
    (tags "resistor SMD 0402")
    (property "Author" "Antmicro")
    (property "License" "Apache-2.0")
    (property "MPN" "ERA-2AEB1542X")
    (property "Manufacturer" "Panasonic")
    (property "Sheetfile" "pow-cycl-curr-meas.kicad_sch")
    (property "Sheetname" "Power Cycling & Current Measurement")
    (property "Tolerance" "0.1%")
    (property "Val" "15k4")
    (property "ki_description" "SMD Chip Resistor, 15.4 kohm, ± 0.1%, 63 mW, 0402 [1005 Metric], Thin Film")
    (property "ki_keywords" "0402, SMT, RESISTOR, PASSIVE")
    (attr smd)
    (fp_text reference "R59" (at 3.05 -0.45 180) (layer "F.SilkS")
        (effects (font (size 0.7 0.7) (thickness 0.15)) (justify left bottom))
    )
    (fp_text value "R_15k4_0.1%_0402" (at -1.011843 1.772047 180) (layer "F.Fab")
        (effects (font (size 0.7 0.7) (thickness 0.15)) (justify left bottom))
    )
    (fp_text user "${REFERENCE}" (at -0.95 3.168 180) (layer "F.Fab") hide
        (effects (font (size 0.7 0.7) (thickness 0.15)) (justify left bottom))
    )
    (fp_text user "Author: Antmicro" (at -0.95 4.169 180) (layer "F.Fab") hide
        (effects (font (size 0.7 0.7) (thickness 0.15)) (justify left bottom))
    )
    (fp_text user "License: Apache-2.0" (at -0.95 5.169 180) (layer "F.Fab") hide
        (effects (font (size 0.7 0.7) (thickness 0.15)) (justify left bottom))
    )
    (fp_rect (start -0.925 -0.47) (end 0.925 0.47)
      (stroke (width 0.05) (type default)) (fill none) (layer "F.CrtYd"))
    (fp_rect (start -0.5 -0.25) (end 0.5 0.25)
      (stroke (width 0.15) (type solid)) (fill none) (layer "F.Fab"))
    (pad "1" smd roundrect (at -0.48 0 180) (size 0.59 0.64) (layers "F.Cu" "F.Paste" "F.Mask") (roundrect_rratio 0.25)
      (net 144 "Net-(R2-Pad1)") (pintype "passive"))
    (pad "2" smd roundrect (at 0.48 0 180) (size 0.59 0.64) (layers "F.Cu" "F.Paste" "F.Mask") (roundrect_rratio 0.25)
      (net 4 "GND") (pintype "passive"))
  )
	(footprint "antmicro-footprints:TPD2E009DRTR" (layer "F.Cu")
    (at 147.9 96.9)
    (property "Author" "Antmicro")
    (property "License" "Apache-2.0")
    (property "MPN" "PESD5V0S2BQA")
    (property "Manufacturer" "Nexperia")
    (property "Sheetfile" "pow-cycl-curr-meas.kicad_sch")
    (property "Sheetname" "Power Cycling & Current Measurement")
    (property "ki_description" "TVS diode array, 30 kV, SOT-1215, 5V, 45 pF")
    (property "ki_keywords" "SMT, DIODE, SEMICONDUCTOR, TVS, ESD")
    (attr smd)
    (fp_text reference "D20" (at -0.8 -0.85) (layer "F.SilkS")
        (effects (font (size 0.7 0.7) (thickness 0.15)) (justify left bottom))
    )
    (fp_text value "PESD5V0S2BQA" (at 5.608 1.306) (layer "F.Fab")
        (effects (font (size 0.7 0.7) (thickness 0.15)) (justify left bottom))
    )
    (fp_text user "${REFERENCE}" (at -0.949 4.506) (layer "F.Fab") hide
        (effects (font (size 0.7 0.7) (thickness 0.15)) (justify left bottom))
    )
    (fp_text user "Author: Antmicro" (at -0.949 3.306) (layer "F.Fab") hide
        (effects (font (size 0.7 0.7) (thickness 0.15)) (justify left bottom))
    )
    (fp_text user "License: Apache-2.0" (at -0.949 5.706) (layer "F.Fab") hide
        (effects (font (size 0.7 0.7) (thickness 0.15)) (justify left bottom))
    )
    (fp_line (start 0.03 -0.499) (end 0.4 -0.499)
      (stroke (width 0.15) (type solid)) (layer "F.SilkS"))
    (fp_line (start 0.03 0.499) (end 0.4 0.499)
      (stroke (width 0.15) (type solid)) (layer "F.SilkS"))
    (fp_line (start 0.4 -0.419) (end 0.4 -0.499)
      (stroke (width 0.15) (type solid)) (layer "F.SilkS"))
    (fp_line (start 0.4 0.42) (end 0.4 0.499)
      (stroke (width 0.15) (type solid)) (layer "F.SilkS"))
    (fp_circle (center -0.5 -0.6) (end -0.45 -0.6)
      (stroke (width 0.15) (type solid)) (fill solid) (layer "F.SilkS"))
    (fp_rect (start -0.8 -0.59) (end 0.8 0.59)
      (stroke (width 0.05) (type solid)) (fill none) (layer "F.CrtYd"))
    (fp_line (start -0.4 -0.499) (end 0.4 -0.499)
      (stroke (width 0.15) (type solid)) (layer "F.Fab"))
    (fp_line (start -0.4 0.499) (end -0.4 -0.499)
      (stroke (width 0.15) (type solid)) (layer "F.Fab"))
    (fp_line (start 0.4 -0.499) (end 0.4 0.499)
      (stroke (width 0.15) (type solid)) (layer "F.Fab"))
    (fp_line (start 0.4 0.499) (end -0.4 0.499)
      (stroke (width 0.15) (type solid)) (layer "F.Fab"))
    (pad "1" smd rect (at -0.52 -0.349) (size 0.46 0.2) (layers "F.Cu" "F.Paste" "F.Mask")
      (net 90 "/Power Cycling & Current Measurement/V_ADC1") (pinfunction "IO1") (pintype "passive"))
    (pad "2" smd rect (at -0.52 0.348) (size 0.46 0.2) (layers "F.Cu" "F.Paste" "F.Mask")
      (net 88 "unconnected-(D20-IO2-Pad2)") (pinfunction "IO2") (pintype "passive+no_connect"))
    (pad "3" smd rect (at 0.52 0) (size 0.46 0.2) (layers "F.Cu" "F.Paste" "F.Mask")
      (net 4 "GND") (pinfunction "GND") (pintype "passive"))
  )
	(footprint "antmicro-footprints:Vishay_PowerPAK_1212-8_Single" (layer "F.Cu")
    (at 137.5 86.3 90)
    (descr "PowerPAK 1212-8 Single")
    (tags "Vishay PowerPAK 1212-8 Single")
    (property "Author" "Antmicro")
    (property "License" "Apache-2.0")
    (property "MPN" "SI7613DN-T1-GE3")
    (property "Manufacturer" "Vishay")
    (property "Sheetfile" "power-switch.kicad_sch")
    (property "Sheetname" "Power switch 2")
    (property "ki_description" "Power MOSFET, P Channel, 20 V, 35 A, 0.0072 ohm, PowerPAK 1212, Surface Mount")
    (property "ki_keywords" "SMT, TRANSISTOR, SEMICONDUCTOR, MOSFET, PMOS")
    (attr smd)
    (fp_text reference "QB2" (at -2.9 0.4 180) (layer "F.SilkS")
        (effects (font (size 0.7 0.7) (thickness 0.15)) (justify left bottom))
    )
    (fp_text value "SI7613DN-T1-GE3" (at 0 2.7 90) (layer "F.Fab")
        (effects (font (size 0.7 0.7) (thickness 0.15)) (justify left bottom))
    )
    (fp_text user "License: Apache-2.0" (at -8 7.1 90) (layer "F.Fab") hide
        (effects (font (size 0.7 0.7) (thickness 0.15)) (justify left bottom))
    )
    (fp_text user "Author: Antmicro" (at -8 5.9 90) (layer "F.Fab") hide
        (effects (font (size 0.7 0.7) (thickness 0.15)) (justify left bottom))
    )
    (fp_text user "${REFERENCE}" (at -8 4.7 90) (layer "F.Fab") hide
        (effects (font (size 0.7 0.7) (thickness 0.15)) (justify left bottom))
    )
    (fp_line (start -1.651 -1.651) (end -1.651 -1.317)
      (stroke (width 0.15) (type solid)) (layer "F.SilkS"))
    (fp_line (start -1.651 -1.651) (end 1.648 -1.651)
      (stroke (width 0.15) (type solid)) (layer "F.SilkS"))
    (fp_line (start -1.635 1.3) (end -1.635 1.634)
      (stroke (width 0.15) (type solid)) (layer "F.SilkS"))
    (fp_line (start -1.635 1.634) (end 1.634 1.634)
      (stroke (width 0.15) (type solid)) (layer "F.SilkS"))
    (fp_line (start 1.634 1.3) (end 1.634 1.634)
      (stroke (width 0.15) (type solid)) (layer "F.SilkS"))
    (fp_line (start 1.648 -1.651) (end 1.648 -1.317)
      (stroke (width 0.15) (type solid)) (layer "F.SilkS"))
    (fp_circle (center -1.9 -1.4) (end -1.85 -1.4)
      (stroke (width 0.15) (type solid)) (fill solid) (layer "F.SilkS"))
    (fp_rect (start -2 -1.8) (end 2 1.798)
      (stroke (width 0.05) (type solid)) (fill none) (layer "F.CrtYd"))
    (fp_line (start -1.6425 -1.4175) (end -1.4175 -1.6425)
      (stroke (width 0.15) (type solid)) (layer "F.Fab"))
    (fp_rect (start -1.651 -1.651) (end 1.648 1.648)
      (stroke (width 0.15) (type solid)) (fill none) (layer "F.Fab"))
    (pad "1" smd rect (at -1.436 -0.99 90) (size 0.99 0.405) (layers "F.Cu" "F.Paste" "F.Mask")
      (net 11 "VCC12V0") (pinfunction "S") (pintype "passive"))
    (pad "2" smd rect (at -1.436 -0.332 90) (size 0.99 0.405) (layers "F.Cu" "F.Paste" "F.Mask")
      (net 11 "VCC12V0") (pinfunction "S") (pintype "passive"))
    (pad "3" smd rect (at -1.436 0.33 90) (size 0.99 0.405) (layers "F.Cu" "F.Paste" "F.Mask")
      (net 11 "VCC12V0") (pinfunction "S") (pintype "passive"))
    (pad "4" smd rect (at -1.436 0.988 90) (size 0.99 0.405) (layers "F.Cu" "F.Paste" "F.Mask")
      (net 100 "Net-(QB2-G)") (pinfunction "G") (pintype "passive"))
    (pad "5" smd custom (at 0.557 0 90) (size 1.725 2.235) (layers "F.Cu" "F.Paste" "F.Mask")
      (net 22 "C_MEAS_2") (pinfunction "D") (pintype "passive") (zone_connect 2)
      (options (clearance outline) (anchor rect))
      (primitives
        (gr_poly
          (pts
            (xy 0.8625 0.1275)
            (xy 0.8625 -0.1275)
            (xy 1.3725 -0.1275)
            (xy 1.3725 -0.5325)
            (xy 0.8625 -0.5325)
            (xy 0.8625 -0.7875)
            (xy 1.3725 -0.7875)
            (xy 1.3725 -1.195)
            (xy 0.6125 -1.195)
            (xy 0.6125 1.195)
            (xy 1.3725 1.195)
            (xy 1.3725 0.7875)
            (xy 0.8625 0.7875)
            (xy 0.8625 0.5325)
            (xy 1.3725 0.5325)
            (xy 1.3725 0.1275)
          )
          (width 0) (fill yes))
      ))
  )
	(footprint "antmicro-footprints:R_0603_1608Metric" (layer "F.Cu")
    (at 166 53.85)
    (descr "Resistor SMD 0603")
    (tags "resistor SMD 0603")
    (property "Author" "Antmicro")
    (property "License" "Apache-2.0")
    (property "MPN" "CR0603-FX-4701ELF")
    (property "Manufacturer" "Bourns")
    (property "Sheetfile" "d1600e-psu-breakout-board.kicad_sch")
    (property "Sheetname" "")
    (property "Tolerance" "1%")
    (property "Val" "4k7")
    (property "ki_description" "SMD Chip Resistor, 4.7 kohm, ± 1%, 100 mW, 0603 [1608 Metric], Thick Film, General Purpose")
    (property "ki_keywords" "0603, SMT, RESISTOR, PASSIVE")
    (attr smd)
    (fp_text reference "R52" (at -1.1 1.6) (layer "F.SilkS")
        (effects (font (size 0.7 0.7) (thickness 0.15)) (justify left bottom))
    )
    (fp_text value "R_4k7_0603" (at 0 1.6) (layer "F.Fab")
        (effects (font (size 0.7 0.7) (thickness 0.15)) (justify left bottom))
    )
    (fp_text user "${REFERENCE}" (at -1.25 3.898) (layer "F.Fab") hide
        (effects (font (size 0.7 0.7) (thickness 0.15)) (justify left bottom))
    )
    (fp_text user "License: Apache-2.0" (at -1.25 5.9) (layer "F.Fab") hide
        (effects (font (size 0.7 0.7) (thickness 0.15)) (justify left bottom))
    )
    (fp_text user "Author: Antmicro" (at -1.25 4.9) (layer "F.Fab") hide
        (effects (font (size 0.7 0.7) (thickness 0.15)) (justify left bottom))
    )
    (fp_line (start -0.15 -0.4) (end 0.15 -0.4)
      (stroke (width 0.15) (type solid)) (layer "F.SilkS"))
    (fp_line (start -0.15 0.4) (end 0.15 0.4)
      (stroke (width 0.15) (type solid)) (layer "F.SilkS"))
    (fp_rect (start -1.25 -0.65) (end 1.25 0.65)
      (stroke (width 0.05) (type solid)) (fill none) (layer "F.CrtYd"))
    (fp_rect (start -0.8 -0.4) (end 0.8 0.4)
      (stroke (width 0.15) (type solid)) (fill none) (layer "F.Fab"))
    (pad "1" smd roundrect (at -0.7 0) (size 0.8 1) (layers "F.Cu" "F.Paste" "F.Mask") (roundrect_rratio 0.2)
      (net 52 "Net-(D7-A)") (pintype "passive"))
    (pad "2" smd roundrect (at 0.7 0) (size 0.8 1) (layers "F.Cu" "F.Paste" "F.Mask") (roundrect_rratio 0.2)
      (net 45 "LOAD_4") (pintype "passive"))
  )
	(footprint "antmicro-footprints:R_0402_1005Metric" (layer "F.Cu")
    (at 130.95 90.4 90)
    (descr "Resistor SMD 0402")
    (tags "resistor SMD 0402")
    (property "Author" "Antmicro")
    (property "License" "Apache-2.0")
    (property "MPN" "CR0402-FX-2R00GLF")
    (property "Manufacturer" "Bourns")
    (property "Sheetfile" "power-switch.kicad_sch")
    (property "Sheetname" "Power switch 2")
    (property "Tolerance" "1%")
    (property "Val" "2R")
    (property "ki_description" "SMD Chip Resistor")
    (property "ki_keywords" "0402, SMT, RESISTOR, PASSIVE")
    (attr smd)
    (fp_text reference "R63" (at -1.75 -0.65 90) (layer "F.SilkS")
        (effects (font (size 0.7 0.7) (thickness 0.15)) (justify left bottom))
    )
    (fp_text value "R_2R_0402" (at -1.011843 1.772047 90) (layer "F.Fab")
        (effects (font (size 0.7 0.7) (thickness 0.15)) (justify left bottom))
    )
    (fp_text user "License: Apache-2.0" (at -0.95 5.169 90) (layer "F.Fab") hide
        (effects (font (size 0.7 0.7) (thickness 0.15)) (justify left bottom))
    )
    (fp_text user "Author: Antmicro" (at -0.95 4.169 90) (layer "F.Fab") hide
        (effects (font (size 0.7 0.7) (thickness 0.15)) (justify left bottom))
    )
    (fp_text user "${REFERENCE}" (at -0.95 3.168 90) (layer "F.Fab") hide
        (effects (font (size 0.7 0.7) (thickness 0.15)) (justify left bottom))
    )
    (fp_rect (start -0.925 -0.47) (end 0.925 0.47)
      (stroke (width 0.05) (type default)) (fill none) (layer "F.CrtYd"))
    (fp_rect (start -0.5 -0.25) (end 0.5 0.25)
      (stroke (width 0.15) (type solid)) (fill none) (layer "F.Fab"))
    (pad "1" smd roundrect (at -0.48 0 90) (size 0.59 0.64) (layers "F.Cu" "F.Paste" "F.Mask") (roundrect_rratio 0.25)
      (net 84 "Net-(D16-A)") (pintype "passive"))
    (pad "2" smd roundrect (at 0.48 0 90) (size 0.59 0.64) (layers "F.Cu" "F.Paste" "F.Mask") (roundrect_rratio 0.25)
      (net 94 "Net-(QA2-G)") (pintype "passive"))
  )
)
